(kicad_pcb
	(version 20260206)
	(generator "pcbnew")
	(generator_version "10.0")
	(general
		(thickness 1.6)
		(legacy_teardrops no)
	)
	(paper "A4")
	(title_block
		(title "peb — Lightning_PEB_BRD.brd")
		(comment 1 "Lightning (Wiwynn / Facebook NVMe JBOF) / footprints 277-284 of 2563")
	)
	(layers
		(0 "F.Cu" signal "TOP")
		(4 "In1.Cu" signal "L2GND")
		(6 "In2.Cu" signal "L3")
		(8 "In3.Cu" signal "L4VCC")
		(10 "In4.Cu" signal "L5VCC")
		(12 "In5.Cu" signal "L6")
		(14 "In6.Cu" signal "L7GND")
		(2 "B.Cu" signal "BOTTOM")
		(9 "F.Adhes" user "F.Adhesive")
		(11 "B.Adhes" user "B.Adhesive")
		(13 "F.Paste" user "Package Geometry/Pastemask Top")
		(15 "B.Paste" user "Package Geometry/Pastemask Bottom")
		(5 "F.SilkS" user "Ref Des/Silkscreen Top")
		(7 "B.SilkS" user "Ref Des/Silkscreen Bottom")
		(1 "F.Mask" user "Board Geometry/Soldermask Top")
		(3 "B.Mask" user "Board Geometry/Soldermask Bottom")
		(17 "Dwgs.User" user "User.Drawings")
		(19 "Cmts.User" user "User.Comments")
		(21 "Eco1.User" user "User.Eco1")
		(23 "Eco2.User" user "User.Eco2")
		(25 "Edge.Cuts" user "Board Geometry/Outline")
		(27 "Margin" user)
		(31 "F.CrtYd" user "Package Geometry/Place Bound Top")
		(29 "B.CrtYd" user "Package Geometry/Place Bound Bottom")
		(35 "F.Fab" user "Ref Des/Assembly Top")
		(33 "B.Fab" user "Ref Des/Assembly Bottom")
	)
	(footprint ""
		(layer "F.Cu")
		(at 12.2936 -68.834)
		(property "Reference" "C620"
			(at 0 0 0)
			(layer "F.SilkS")
			(hide yes)
			(effects
				(font
					(size 1.27 1.27)
				)
			)
		)
		(property "Value" "SCD1U16V2KX-3GP"
			(at 1.1811 -2.7051 0)
			(unlocked yes)
			(layer "F.Fab")
			(hide yes)
			(effects
				(font
					(size 1.016 1.016)
					(thickness 0.1524)
				)
			)
		)
		(property "Device Type" "C402H22"
			(at 1.1811 -4.2291 0)
			(unlocked yes)
			(layer "F.Fab")
			(hide yes)
			(effects
				(font
					(size 1.016 1.016)
					(thickness 0.1524)
				)
			)
		)
		(duplicate_pad_numbers_are_jumpers no)
		(fp_rect
			(start -0.4318 0.9525)
			(end 0.4318 -0.9525)
			(stroke
				(width 0)
				(type default)
			)
			(fill no)
			(layer "F.CrtYd")
		)
		(fp_rect
			(start -0.4318 0.9525)
			(end 0.4318 -0.9525)
			(stroke
				(width 0)
				(type default)
			)
			(fill no)
			(layer "F.Fab")
		)
		(pad "1" smd custom
			(at 0 -0.4445)
			(size 0.1524 0.1524)
			(layers "F.Cu" "F.Mask" "F.Paste")
			(net "P1V5_I210")
			(options
				(clearance outline)
				(anchor circle)
			)
			(primitives
				(gr_poly
					(pts
						(arc
							(start 0.3048 -0.2032)
							(mid 0.275042 -0.275042)
							(end 0.2032 -0.3048)
						)
						(arc
							(start -0.2032 -0.3048)
							(mid -0.275042 -0.275042)
							(end -0.3048 -0.2032)
						)
						(arc
							(start -0.3048 0.2032)
							(mid -0.275042 0.275042)
							(end -0.2032 0.3048)
						)
						(arc
							(start 0.2032 0.3048)
							(mid 0.275042 0.275042)
							(end 0.3048 0.2032)
						)
					)
					(width 0)
					(fill yes)
				)
			)
		)
		(pad "2" smd custom
			(at 0 0.4445)
			(size 0.1524 0.1524)
			(layers "F.Cu" "F.Mask" "F.Paste")
			(net "GND")
			(options
				(clearance outline)
				(anchor circle)
			)
			(primitives
				(gr_poly
					(pts
						(arc
							(start 0.3048 -0.2032)
							(mid 0.275042 -0.275042)
							(end 0.2032 -0.3048)
						)
						(arc
							(start -0.2032 -0.3048)
							(mid -0.275042 -0.275042)
							(end -0.3048 -0.2032)
						)
						(arc
							(start -0.3048 0.2032)
							(mid -0.275042 0.275042)
							(end -0.2032 0.3048)
						)
						(arc
							(start 0.2032 0.3048)
							(mid 0.275042 0.275042)
							(end 0.3048 0.2032)
						)
					)
					(width 0)
					(fill yes)
				)
			)
		)
	)
	(footprint ""
		(layer "F.Cu")
		(at 156.718 -95.9104)
		(property "Reference" "R97"
			(at 0 0 0)
			(layer "F.SilkS")
			(hide yes)
			(effects
				(font
					(size 1.27 1.27)
				)
			)
		)
		(property "Value" "10KR2F-2-GP"
			(at 0.064008 -3.993896 0)
			(unlocked yes)
			(layer "F.Fab")
			(hide yes)
			(effects
				(font
					(size 1.016 1.016)
					(thickness 0.1524)
				)
			)
		)
		(property "Device Type" "R402H16"
			(at 0.064008 -5.517896 0)
			(unlocked yes)
			(layer "F.Fab")
			(hide yes)
			(effects
				(font
					(size 1.016 1.016)
					(thickness 0.1524)
				)
			)
		)
		(duplicate_pad_numbers_are_jumpers no)
		(fp_line
			(start -0.508 -0.9398)
			(end -0.508 0.9398)
			(stroke
				(width 0.1524)
				(type default)
			)
			(layer "F.SilkS")
		)
		(fp_line
			(start 0.508 -0.9398)
			(end -0.508 -0.9398)
			(stroke
				(width 0.1524)
				(type default)
			)
			(layer "F.SilkS")
		)
		(fp_rect
			(start -0.508 0.9398)
			(end 0.508 -0.9398)
			(stroke
				(width 0)
				(type default)
			)
			(fill no)
			(layer "F.CrtYd")
		)
		(fp_rect
			(start -0.508 0.9398)
			(end 0.508 -0.9398)
			(stroke
				(width 0)
				(type default)
			)
			(fill no)
			(layer "F.Fab")
		)
		(pad "1" smd custom
			(at 0 -0.4445)
			(size 0.1397 0.1397)
			(layers "F.Cu" "F.Mask" "F.Paste")
			(net "GND")
			(options
				(clearance outline)
				(anchor circle)
			)
			(primitives
				(gr_poly
					(pts
						(arc
							(start -0.1778 -0.2794)
							(mid -0.249642 -0.249642)
							(end -0.2794 -0.1778)
						)
						(arc
							(start -0.2794 0.1778)
							(mid -0.249642 0.249642)
							(end -0.1778 0.2794)
						)
						(arc
							(start 0.1778 0.2794)
							(mid 0.249642 0.249642)
							(end 0.2794 0.1778)
						)
						(arc
							(start 0.2794 -0.1778)
							(mid 0.249642 -0.249642)
							(end 0.1778 -0.2794)
						)
					)
					(width 0)
					(fill yes)
				)
			)
		)
		(pad "2" smd custom
			(at 0 0.4445)
			(size 0.1397 0.1397)
			(layers "F.Cu" "F.Mask" "F.Paste")
			(net "CLKGNE_SS_EN")
			(options
				(clearance outline)
				(anchor circle)
			)
			(primitives
				(gr_poly
					(pts
						(arc
							(start -0.1778 -0.2794)
							(mid -0.249642 -0.249642)
							(end -0.2794 -0.1778)
						)
						(arc
							(start -0.2794 0.1778)
							(mid -0.249642 0.249642)
							(end -0.1778 0.2794)
						)
						(arc
							(start 0.1778 0.2794)
							(mid 0.249642 0.249642)
							(end 0.2794 0.1778)
						)
						(arc
							(start 0.2794 -0.1778)
							(mid 0.249642 -0.249642)
							(end 0.1778 -0.2794)
						)
					)
					(width 0)
					(fill yes)
				)
			)
		)
	)
	(footprint ""
		(layer "F.Cu")
		(at 20.574 -148.336)
		(property "Reference" "C187"
			(at 0 0 0)
			(layer "F.SilkS")
			(hide yes)
			(effects
				(font
					(size 1.27 1.27)
				)
			)
		)
		(property "Value" "SCD1U16V2KX-3GP"
			(at 1.1811 -2.7051 0)
			(unlocked yes)
			(layer "F.Fab")
			(hide yes)
			(effects
				(font
					(size 1.016 1.016)
					(thickness 0.1524)
				)
			)
		)
		(property "Device Type" "C402H22"
			(at 1.1811 -4.2291 0)
			(unlocked yes)
			(layer "F.Fab")
			(hide yes)
			(effects
				(font
					(size 1.016 1.016)
					(thickness 0.1524)
				)
			)
		)
		(duplicate_pad_numbers_are_jumpers no)
		(fp_rect
			(start -0.4318 0.9525)
			(end 0.4318 -0.9525)
			(stroke
				(width 0)
				(type default)
			)
			(fill no)
			(layer "F.CrtYd")
		)
		(fp_rect
			(start -0.4318 0.9525)
			(end 0.4318 -0.9525)
			(stroke
				(width 0)
				(type default)
			)
			(fill no)
			(layer "F.Fab")
		)
		(pad "1" smd custom
			(at 0 -0.4445)
			(size 0.1524 0.1524)
			(layers "F.Cu" "F.Mask" "F.Paste")
			(net "P3V3_STBY")
			(options
				(clearance outline)
				(anchor circle)
			)
			(primitives
				(gr_poly
					(pts
						(arc
							(start 0.3048 -0.2032)
							(mid 0.275042 -0.275042)
							(end 0.2032 -0.3048)
						)
						(arc
							(start -0.2032 -0.3048)
							(mid -0.275042 -0.275042)
							(end -0.3048 -0.2032)
						)
						(arc
							(start -0.3048 0.2032)
							(mid -0.275042 0.275042)
							(end -0.2032 0.3048)
						)
						(arc
							(start 0.2032 0.3048)
							(mid 0.275042 0.275042)
							(end 0.3048 0.2032)
						)
					)
					(width 0)
					(fill yes)
				)
			)
		)
		(pad "2" smd custom
			(at 0 0.4445)
			(size 0.1524 0.1524)
			(layers "F.Cu" "F.Mask" "F.Paste")
			(net "GND")
			(options
				(clearance outline)
				(anchor circle)
			)
			(primitives
				(gr_poly
					(pts
						(arc
							(start 0.3048 -0.2032)
							(mid 0.275042 -0.275042)
							(end 0.2032 -0.3048)
						)
						(arc
							(start -0.2032 -0.3048)
							(mid -0.275042 -0.275042)
							(end -0.3048 -0.2032)
						)
						(arc
							(start -0.3048 0.2032)
							(mid -0.275042 0.275042)
							(end -0.2032 0.3048)
						)
						(arc
							(start 0.2032 0.3048)
							(mid 0.275042 0.275042)
							(end 0.3048 0.2032)
						)
					)
					(width 0)
					(fill yes)
				)
			)
		)
	)
	(footprint ""
		(layer "F.Cu")
		(at 83.081368 -75.1586 90)
		(property "Reference" "C283"
			(at 0 0 90)
			(layer "F.SilkS")
			(hide yes)
			(effects
				(font
					(size 1.27 1.27)
				)
			)
		)
		(property "Value" "SCD01U16V2KX-3GP"
			(at 1.1811 -2.7051 90)
			(unlocked yes)
			(layer "F.Fab")
			(hide yes)
			(effects
				(font
					(size 1.016 1.016)
					(thickness 0.1524)
				)
			)
		)
		(property "Device Type" "C402H22"
			(at 1.1811 -4.2291 90)
			(unlocked yes)
			(layer "F.Fab")
			(hide yes)
			(effects
				(font
					(size 1.016 1.016)
					(thickness 0.1524)
				)
			)
		)
		(duplicate_pad_numbers_are_jumpers no)
		(fp_rect
			(start -0.4318 0.9525)
			(end 0.4318 -0.9525)
			(stroke
				(width 0)
				(type default)
			)
			(fill no)
			(layer "F.CrtYd")
		)
		(fp_rect
			(start -0.4318 0.9525)
			(end 0.4318 -0.9525)
			(stroke
				(width 0)
				(type default)
			)
			(fill no)
			(layer "F.Fab")
		)
		(pad "1" smd custom
			(at 0 -0.4445 90)
			(size 0.1524 0.1524)
			(layers "F.Cu" "F.Mask" "F.Paste")
			(net "P3V3_STBY")
			(options
				(clearance outline)
				(anchor circle)
			)
			(primitives
				(gr_poly
					(pts
						(arc
							(start 0.3048 -0.2032)
							(mid 0.275042 -0.275042)
							(end 0.2032 -0.3048)
						)
						(arc
							(start -0.2032 -0.3048)
							(mid -0.275042 -0.275042)
							(end -0.3048 -0.2032)
						)
						(arc
							(start -0.3048 0.2032)
							(mid -0.275042 0.275042)
							(end -0.2032 0.3048)
						)
						(arc
							(start 0.2032 0.3048)
							(mid 0.275042 0.275042)
							(end 0.3048 0.2032)
						)
					)
					(width 0)
					(fill yes)
				)
			)
		)
		(pad "2" smd custom
			(at 0 0.4445 90)
			(size 0.1524 0.1524)
			(layers "F.Cu" "F.Mask" "F.Paste")
			(net "GND")
			(options
				(clearance outline)
				(anchor circle)
			)
			(primitives
				(gr_poly
					(pts
						(arc
							(start 0.3048 -0.2032)
							(mid 0.275042 -0.275042)
							(end 0.2032 -0.3048)
						)
						(arc
							(start -0.2032 -0.3048)
							(mid -0.275042 -0.275042)
							(end -0.3048 -0.2032)
						)
						(arc
							(start -0.3048 0.2032)
							(mid -0.275042 0.275042)
							(end -0.2032 0.3048)
						)
						(arc
							(start 0.2032 0.3048)
							(mid 0.275042 0.275042)
							(end 0.3048 0.2032)
						)
					)
					(width 0)
					(fill yes)
				)
			)
		)
	)
	(footprint ""
		(layer "F.Cu")
		(at 61.2902 -161.8996 180)
		(property "Reference" "PC18"
			(at 0 0 180)
			(layer "F.SilkS")
			(hide yes)
			(effects
				(font
					(size 1.27 1.27)
				)
			)
		)
		(property "Value" "SCD01U25V2KX-3GP"
			(at 1.1811 -2.7051 180)
			(unlocked yes)
			(layer "F.Fab")
			(hide yes)
			(effects
				(font
					(size 1.016 1.016)
					(thickness 0.1524)
				)
			)
		)
		(property "Device Type" "C402H22"
			(at 1.1811 -4.2291 180)
			(unlocked yes)
			(layer "F.Fab")
			(hide yes)
			(effects
				(font
					(size 1.016 1.016)
					(thickness 0.1524)
				)
			)
		)
		(duplicate_pad_numbers_are_jumpers no)
		(fp_rect
			(start -0.4318 0.9525)
			(end 0.4318 -0.9525)
			(stroke
				(width 0)
				(type default)
			)
			(fill no)
			(layer "F.CrtYd")
		)
		(fp_rect
			(start -0.4318 0.9525)
			(end 0.4318 -0.9525)
			(stroke
				(width 0)
				(type default)
			)
			(fill no)
			(layer "F.Fab")
		)
		(pad "1" smd custom
			(at 0 -0.4445 180)
			(size 0.1524 0.1524)
			(layers "F.Cu" "F.Mask" "F.Paste")
			(net "P1V53_PWR")
			(options
				(clearance outline)
				(anchor circle)
			)
			(primitives
				(gr_poly
					(pts
						(arc
							(start 0.3048 -0.2032)
							(mid 0.275042 -0.275042)
							(end 0.2032 -0.3048)
						)
						(arc
							(start -0.2032 -0.3048)
							(mid -0.275042 -0.275042)
							(end -0.3048 -0.2032)
						)
						(arc
							(start -0.3048 0.2032)
							(mid -0.275042 0.275042)
							(end -0.2032 0.3048)
						)
						(arc
							(start 0.2032 0.3048)
							(mid 0.275042 0.275042)
							(end 0.3048 0.2032)
						)
					)
					(width 0)
					(fill yes)
				)
			)
		)
		(pad "2" smd custom
			(at 0 0.4445 180)
			(size 0.1524 0.1524)
			(layers "F.Cu" "F.Mask" "F.Paste")
			(net "VR_P1V538_STBY_FB")
			(options
				(clearance outline)
				(anchor circle)
			)
			(primitives
				(gr_poly
					(pts
						(arc
							(start 0.3048 -0.2032)
							(mid 0.275042 -0.275042)
							(end 0.2032 -0.3048)
						)
						(arc
							(start -0.2032 -0.3048)
							(mid -0.275042 -0.275042)
							(end -0.3048 -0.2032)
						)
						(arc
							(start -0.3048 0.2032)
							(mid -0.275042 0.275042)
							(end -0.2032 0.3048)
						)
						(arc
							(start 0.2032 0.3048)
							(mid 0.275042 0.275042)
							(end 0.3048 0.2032)
						)
					)
					(width 0)
					(fill yes)
				)
			)
		)
	)
	(footprint ""
		(layer "F.Cu")
		(at 257.670554 -10.999724 180)
		(property "Reference" "C42"
			(at 0 0 180)
			(layer "F.SilkS")
			(hide yes)
			(effects
				(font
					(size 1.27 1.27)
				)
			)
		)
		(property "Value" "SCD1U10V2KX-5GP"
			(at 1.1811 -2.7051 180)
			(unlocked yes)
			(layer "F.Fab")
			(hide yes)
			(effects
				(font
					(size 1.016 1.016)
					(thickness 0.1524)
				)
			)
		)
		(property "Device Type" "C402H22"
			(at 1.1811 -4.2291 180)
			(unlocked yes)
			(layer "F.Fab")
			(hide yes)
			(effects
				(font
					(size 1.016 1.016)
					(thickness 0.1524)
				)
			)
		)
		(duplicate_pad_numbers_are_jumpers no)
		(fp_rect
			(start -0.4318 0.9525)
			(end 0.4318 -0.9525)
			(stroke
				(width 0)
				(type default)
			)
			(fill no)
			(layer "F.CrtYd")
		)
		(fp_rect
			(start -0.4318 0.9525)
			(end 0.4318 -0.9525)
			(stroke
				(width 0)
				(type default)
			)
			(fill no)
			(layer "F.Fab")
		)
		(pad "1" smd custom
			(at 0 -0.4445 180)
			(size 0.1524 0.1524)
			(layers "F.Cu" "F.Mask" "F.Paste")
			(net "P3V3_STBY")
			(options
				(clearance outline)
				(anchor circle)
			)
			(primitives
				(gr_poly
					(pts
						(arc
							(start 0.3048 -0.2032)
							(mid 0.275042 -0.275042)
							(end 0.2032 -0.3048)
						)
						(arc
							(start -0.2032 -0.3048)
							(mid -0.275042 -0.275042)
							(end -0.3048 -0.2032)
						)
						(arc
							(start -0.3048 0.2032)
							(mid -0.275042 0.275042)
							(end -0.2032 0.3048)
						)
						(arc
							(start 0.2032 0.3048)
							(mid 0.275042 0.275042)
							(end 0.3048 0.2032)
						)
					)
					(width 0)
					(fill yes)
				)
			)
		)
		(pad "2" smd custom
			(at 0 0.4445 180)
			(size 0.1524 0.1524)
			(layers "F.Cu" "F.Mask" "F.Paste")
			(net "GND")
			(options
				(clearance outline)
				(anchor circle)
			)
			(primitives
				(gr_poly
					(pts
						(arc
							(start 0.3048 -0.2032)
							(mid 0.275042 -0.275042)
							(end 0.2032 -0.3048)
						)
						(arc
							(start -0.2032 -0.3048)
							(mid -0.275042 -0.275042)
							(end -0.3048 -0.2032)
						)
						(arc
							(start -0.3048 0.2032)
							(mid -0.275042 0.275042)
							(end -0.2032 0.3048)
						)
						(arc
							(start 0.2032 0.3048)
							(mid 0.275042 0.275042)
							(end 0.3048 0.2032)
						)
					)
					(width 0)
					(fill yes)
				)
			)
		)
	)
	(footprint ""
		(layer "F.Cu")
		(at 276.50948 -5.82676 90)
		(property "Reference" "R2904"
			(at 0 0 90)
			(layer "F.SilkS")
			(hide yes)
			(effects
				(font
					(size 1.27 1.27)
				)
			)
		)
		(property "Value" "0R2J-2-GP"
			(at 0.064008 -3.993896 90)
			(unlocked yes)
			(layer "F.Fab")
			(hide yes)
			(effects
				(font
					(size 1.016 1.016)
					(thickness 0.1524)
				)
			)
		)
		(property "Device Type" "R402H16"
			(at 0.064008 -5.517896 90)
			(unlocked yes)
			(layer "F.Fab")
			(hide yes)
			(effects
				(font
					(size 1.016 1.016)
					(thickness 0.1524)
				)
			)
		)
		(duplicate_pad_numbers_are_jumpers no)
		(fp_line
			(start 0.508 -0.9398)
			(end -0.508 -0.9398)
			(stroke
				(width 0.1524)
				(type default)
			)
			(layer "F.SilkS")
		)
		(fp_line
			(start -0.508 -0.9398)
			(end -0.508 0.9398)
			(stroke
				(width 0.1524)
				(type default)
			)
			(layer "F.SilkS")
		)
		(fp_rect
			(start -0.508 0.9398)
			(end 0.508 -0.9398)
			(stroke
				(width 0)
				(type default)
			)
			(fill no)
			(layer "F.CrtYd")
		)
		(fp_rect
			(start -0.508 0.9398)
			(end 0.508 -0.9398)
			(stroke
				(width 0)
				(type default)
			)
			(fill no)
			(layer "F.Fab")
		)
		(pad "1" smd custom
			(at 0 -0.4445 90)
			(size 0.1397 0.1397)
			(layers "F.Cu" "F.Mask" "F.Paste")
			(net "CBL_PRSNT_N_6")
			(options
				(clearance outline)
				(anchor circle)
			)
			(primitives
				(gr_poly
					(pts
						(arc
							(start -0.1778 -0.2794)
							(mid -0.249642 -0.249642)
							(end -0.2794 -0.1778)
						)
						(arc
							(start -0.2794 0.1778)
							(mid -0.249642 0.249642)
							(end -0.1778 0.2794)
						)
						(arc
							(start 0.1778 0.2794)
							(mid 0.249642 0.249642)
							(end 0.2794 0.1778)
						)
						(arc
							(start 0.2794 -0.1778)
							(mid 0.249642 -0.249642)
							(end 0.1778 -0.2794)
						)
					)
					(width 0)
					(fill yes)
				)
			)
		)
		(pad "2" smd custom
			(at 0 0.4445 90)
			(size 0.1397 0.1397)
			(layers "F.Cu" "F.Mask" "F.Paste")
			(net "8644_CBL_PRSNT_R_6")
			(options
				(clearance outline)
				(anchor circle)
			)
			(primitives
				(gr_poly
					(pts
						(arc
							(start -0.1778 -0.2794)
							(mid -0.249642 -0.249642)
							(end -0.2794 -0.1778)
						)
						(arc
							(start -0.2794 0.1778)
							(mid -0.249642 0.249642)
							(end -0.1778 0.2794)
						)
						(arc
							(start 0.1778 0.2794)
							(mid 0.249642 0.249642)
							(end 0.2794 0.1778)
						)
						(arc
							(start 0.2794 -0.1778)
							(mid 0.249642 -0.249642)
							(end 0.1778 -0.2794)
						)
					)
					(width 0)
					(fill yes)
				)
			)
		)
	)
	(footprint ""
		(layer "F.Cu")
		(at 262.255 -26.289 180)
		(property "Reference" "R744"
			(at 0 0 180)
			(layer "F.SilkS")
			(hide yes)
			(effects
				(font
					(size 1.27 1.27)
				)
			)
		)
		(property "Value" "4K7R2F-GP"
			(at 0.064008 -3.993896 180)
			(unlocked yes)
			(layer "F.Fab")
			(hide yes)
			(effects
				(font
					(size 1.016 1.016)
					(thickness 0.1524)
				)
			)
		)
		(property "Device Type" "R402H16"
			(at 0.064008 -5.517896 180)
			(unlocked yes)
			(layer "F.Fab")
			(hide yes)
			(effects
				(font
					(size 1.016 1.016)
					(thickness 0.1524)
				)
			)
		)
		(duplicate_pad_numbers_are_jumpers no)
		(fp_line
			(start 0.508 -0.9398)
			(end -0.508 -0.9398)
			(stroke
				(width 0.1524)
				(type default)
			)
			(layer "F.SilkS")
		)
		(fp_line
			(start -0.508 -0.9398)
			(end -0.508 0.9398)
			(stroke
				(width 0.1524)
				(type default)
			)
			(layer "F.SilkS")
		)
		(fp_rect
			(start -0.508 0.9398)
			(end 0.508 -0.9398)
			(stroke
				(width 0)
				(type default)
			)
			(fill no)
			(layer "F.CrtYd")
		)
		(fp_rect
			(start -0.508 0.9398)
			(end 0.508 -0.9398)
			(stroke
				(width 0)
				(type default)
			)
			(fill no)
			(layer "F.Fab")
		)
		(pad "1" smd custom
			(at 0 -0.4445 180)
			(size 0.1397 0.1397)
			(layers "F.Cu" "F.Mask" "F.Paste")
			(net "P3V3_GPIO")
			(options
				(clearance outline)
				(anchor circle)
			)
			(primitives
				(gr_poly
					(pts
						(arc
							(start -0.1778 -0.2794)
							(mid -0.249642 -0.249642)
							(end -0.2794 -0.1778)
						)
						(arc
							(start -0.2794 0.1778)
							(mid -0.249642 0.249642)
							(end -0.1778 0.2794)
						)
						(arc
							(start 0.1778 0.2794)
							(mid 0.249642 0.249642)
							(end 0.2794 0.1778)
						)
						(arc
							(start 0.2794 -0.1778)
							(mid 0.249642 -0.249642)
							(end 0.1778 -0.2794)
						)
					)
					(width 0)
					(fill yes)
				)
			)
		)
		(pad "2" smd custom
			(at 0 0.4445 180)
			(size 0.1397 0.1397)
			(layers "F.Cu" "F.Mask" "F.Paste")
			(net "IOEXP_INT#_3")
			(options
				(clearance outline)
				(anchor circle)
			)
			(primitives
				(gr_poly
					(pts
						(arc
							(start -0.1778 -0.2794)
							(mid -0.249642 -0.249642)
							(end -0.2794 -0.1778)
						)
						(arc
							(start -0.2794 0.1778)
							(mid -0.249642 0.249642)
							(end -0.1778 0.2794)
						)
						(arc
							(start 0.1778 0.2794)
							(mid 0.249642 0.249642)
							(end 0.2794 0.1778)
						)
						(arc
							(start 0.2794 -0.1778)
							(mid 0.249642 -0.249642)
							(end 0.1778 -0.2794)
						)
					)
					(width 0)
					(fill yes)
				)
			)
		)
	)
)
